(kicad_pcb
	(version 20260206)
	(generator "pcbnew")
	(generator_version "10.0")
	(general
		(thickness 1.6)
		(legacy_teardrops no)
	)
	(paper "A4")
	(title_block
		(title "panther-plus-userver — 13130-1b_20150205.brd")
		(comment 1 "Honey Badger (Wiwynn) / footprint 624 of 1509 (DIMM4), pads 37-43 of 210")
	)
	(layers
		(0 "F.Cu" signal "TOP")
		(4 "In1.Cu" signal "L2")
		(6 "In2.Cu" signal "L3")
		(8 "In3.Cu" signal "L4")
		(10 "In4.Cu" signal "L5")
		(12 "In5.Cu" signal "L6")
		(14 "In6.Cu" signal "L7")
		(16 "In7.Cu" signal "L8")
		(18 "In8.Cu" signal "L9")
		(20 "In9.Cu" signal "L10")
		(22 "In10.Cu" signal "L11")
		(2 "B.Cu" signal "BOTTOM")
		(9 "F.Adhes" user "F.Adhesive")
		(11 "B.Adhes" user "B.Adhesive")
		(13 "F.Paste" user "Package Geometry/Pastemask Top")
		(15 "B.Paste" user "Package Geometry/Pastemask Bottom")
		(5 "F.SilkS" user "Ref Des/Silkscreen Top")
		(7 "B.SilkS" user "Ref Des/Silkscreen Bottom")
		(1 "F.Mask" user "Board Geometry/Soldermask Top")
		(3 "B.Mask" user "Board Geometry/Soldermask Bottom")
		(17 "Dwgs.User" user "User.Drawings")
		(19 "Cmts.User" user "User.Comments")
		(21 "Eco1.User" user "User.Eco1")
		(23 "Eco2.User" user "User.Eco2")
		(25 "Edge.Cuts" user "Board Geometry/Outline")
		(27 "Margin" user)
		(31 "F.CrtYd" user "Package Geometry/Place Bound Top")
		(29 "B.CrtYd" user "Package Geometry/Place Bound Bottom")
		(35 "F.Fab" user "Ref Des/Assembly Top")
		(33 "B.Fab" user "Ref Des/Assembly Bottom")
	)
	(footprint ""
		(layer "F.Cu")
		(at 159.999934 -5.790692)
		(property "Reference" "DIMM4"
			(at 0 0 0)
			(layer "F.SilkS")
			(hide yes)
			(effects
				(font
					(size 1.27 1.27)
				)
			)
		)
		(property "Value" "DDR3-204P-174-COLAY-1-GP"
			(at -40.682164 -17.468088 0)
			(unlocked yes)
			(layer "F.Fab")
			(hide yes)
			(effects
				(font
					(size 1.016 1.016)
					(thickness 0.1524)
				)
			)
		)
		(property "Device Type" "AS0A626-H8SN-7H-COLAY-1"
			(at -40.682164 -18.992088 0)
			(unlocked yes)
			(layer "F.Fab")
			(hide yes)
			(effects
				(font
					(size 1.016 1.016)
					(thickness 0.1524)
				)
			)
		)
		(duplicate_pad_numbers_are_jumpers no)
		(pad "35" smd custom
			(at -21.450046 4.106672)
			(size 0.1143 0.1143)
			(layers "F.Cu" "F.Mask" "F.Paste")
			(net "GND")
			(options
				(clearance outline)
				(anchor circle)
			)
			(primitives
				(gr_poly
					(pts
						(xy 0 0.9017) (xy -0.03175 0.89916) (xy -0.0635 0.889) (xy -0.09144 0.87376) (xy -0.11684 0.85344)
						(xy -0.13716 0.82804) (xy -0.1524 0.8001) (xy -0.16256 0.76835) (xy -0.1651 0.7366) (xy -0.1651 0.11938)
						(xy -0.17272 0.11176) (xy -0.19812 0.0762) (xy -0.2032 0.06604) (xy -0.20701 0.05715) (xy -0.21209 0.04699)
						(xy -0.2159 0.03683) (xy -0.21844 0.02667) (xy -0.22225 0.01524) (xy -0.22352 0.00508) (xy -0.22606 -0.00508)
						(xy -0.22733 -0.01651) (xy -0.22733 -0.02667) (xy -0.2286 -0.0381) (xy -0.22733 -0.04953) (xy -0.22733 -0.05969)
						(xy -0.22606 -0.07112) (xy -0.22352 -0.08128) (xy -0.22225 -0.09144) (xy -0.21844 -0.10287) (xy -0.2159 -0.11303)
						(xy -0.21209 -0.12319) (xy -0.20701 -0.13335) (xy -0.2032 -0.14224) (xy -0.19812 -0.1524) (xy -0.17272 -0.18796)
						(xy -0.1651 -0.19558) (xy -0.1651 -0.7366) (xy -0.16256 -0.76835) (xy -0.1524 -0.8001) (xy -0.13716 -0.82804)
						(xy -0.11684 -0.85344) (xy -0.09144 -0.87376) (xy -0.0635 -0.889) (xy -0.03175 -0.89916) (xy 0 -0.9017)
						(xy 0.03175 -0.89916) (xy 0.0635 -0.889) (xy 0.09144 -0.87376) (xy 0.11684 -0.85344) (xy 0.13716 -0.82804)
						(xy 0.1524 -0.8001) (xy 0.16256 -0.76835) (xy 0.1651 -0.7366) (xy 0.1651 -0.19685) (xy 0.17272 -0.18923)
						(xy 0.17907 -0.18034) (xy 0.18669 -0.17145) (xy 0.19177 -0.16256) (xy 0.19812 -0.15367) (xy 0.20828 -0.13335)
						(xy 0.21971 -0.10287) (xy 0.22225 -0.09271) (xy 0.22479 -0.08128) (xy 0.22606 -0.07112) (xy 0.2286 -0.05969)
						(xy 0.2286 -0.01651) (xy 0.22606 -0.00508) (xy 0.22479 0.00508) (xy 0.22225 0.01651) (xy 0.21971 0.02667)
						(xy 0.20828 0.05715) (xy 0.19812 0.07747) (xy 0.19177 0.08636) (xy 0.18669 0.09525) (xy 0.17907 0.10414)
						(xy 0.17272 0.11303) (xy 0.1651 0.12065) (xy 0.1651 0.7366) (xy 0.16256 0.76835) (xy 0.1524 0.8001)
						(xy 0.13716 0.82804) (xy 0.11684 0.85344) (xy 0.09144 0.87376) (xy 0.0635 0.889) (xy 0.03175 0.89916)
					)
					(width 0)
					(fill yes)
				)
			)
		)
		(pad "36" smd custom
			(at -21.150072 -4.106672)
			(size 0.1143 0.1143)
			(layers "F.Cu" "F.Mask" "F.Paste")
			(net "M_B_DQ11")
			(options
				(clearance outline)
				(anchor circle)
			)
			(primitives
				(gr_poly
					(pts
						(xy 0 0.9017) (xy -0.03175 0.89916) (xy -0.0635 0.889) (xy -0.09144 0.87376) (xy -0.11684 0.85344)
						(xy -0.13716 0.82804) (xy -0.1524 0.8001) (xy -0.16256 0.76835) (xy -0.1651 0.7366) (xy -0.1651 0.19685)
						(xy -0.17272 0.18923) (xy -0.17907 0.18034) (xy -0.18669 0.17145) (xy -0.19177 0.16256) (xy -0.19812 0.15367)
						(xy -0.20828 0.13335) (xy -0.21971 0.10287) (xy -0.22225 0.09271) (xy -0.22479 0.08128) (xy -0.22606 0.07112)
						(xy -0.2286 0.05969) (xy -0.2286 0.01651) (xy -0.22606 0.00508) (xy -0.22479 -0.00508) (xy -0.22225 -0.01651)
						(xy -0.21971 -0.02667) (xy -0.20828 -0.05715) (xy -0.19812 -0.07747) (xy -0.19177 -0.08636) (xy -0.18669 -0.09525)
						(xy -0.17907 -0.10414) (xy -0.17272 -0.11303) (xy -0.1651 -0.12065) (xy -0.1651 -0.7366) (xy -0.16256 -0.76835)
						(xy -0.1524 -0.8001) (xy -0.13716 -0.82804) (xy -0.11684 -0.85344) (xy -0.09144 -0.87376) (xy -0.0635 -0.889)
						(xy -0.03175 -0.89916) (xy 0 -0.9017) (xy 0.03175 -0.89916) (xy 0.0635 -0.889) (xy 0.09144 -0.87376)
						(xy 0.11684 -0.85344) (xy 0.13716 -0.82804) (xy 0.1524 -0.8001) (xy 0.16256 -0.76835) (xy 0.1651 -0.7366)
						(xy 0.1651 -0.11938) (xy 0.17272 -0.11176) (xy 0.19812 -0.0762) (xy 0.2032 -0.06604) (xy 0.20701 -0.05715)
						(xy 0.21209 -0.04699) (xy 0.2159 -0.03683) (xy 0.21844 -0.02667) (xy 0.22225 -0.01524) (xy 0.22352 -0.00508)
						(xy 0.22606 0.00508) (xy 0.22733 0.01651) (xy 0.22733 0.02667) (xy 0.2286 0.0381) (xy 0.22733 0.04953)
						(xy 0.22733 0.05969) (xy 0.22606 0.07112) (xy 0.22352 0.08128) (xy 0.22225 0.09144) (xy 0.21844 0.10287)
						(xy 0.2159 0.11303) (xy 0.21209 0.12319) (xy 0.20701 0.13335) (xy 0.2032 0.14224) (xy 0.19812 0.1524)
						(xy 0.17272 0.18796) (xy 0.1651 0.19558) (xy 0.1651 0.7366) (xy 0.16256 0.76835) (xy 0.1524 0.8001)
						(xy 0.13716 0.82804) (xy 0.11684 0.85344) (xy 0.09144 0.87376) (xy 0.0635 0.889) (xy 0.03175 0.89916)
					)
					(width 0)
					(fill yes)
				)
			)
		)
		(pad "37" smd custom
			(at -20.850098 4.106672)
			(size 0.1143 0.1143)
			(layers "F.Cu" "F.Mask" "F.Paste")
			(net "M_B_DQ20")
			(options
				(clearance outline)
				(anchor circle)
			)
			(primitives
				(gr_poly
					(pts
						(xy 0 0.9017) (xy -0.03175 0.89916) (xy -0.0635 0.889) (xy -0.09144 0.87376) (xy -0.11684 0.85344)
						(xy -0.13716 0.82804) (xy -0.1524 0.8001) (xy -0.16256 0.76835) (xy -0.1651 0.7366) (xy -0.1651 -0.13462)
						(xy -0.17272 -0.14224) (xy -0.19812 -0.1778) (xy -0.2032 -0.18796) (xy -0.20701 -0.19685) (xy -0.21209 -0.20701)
						(xy -0.2159 -0.21717) (xy -0.21844 -0.22733) (xy -0.22225 -0.23876) (xy -0.22352 -0.24892) (xy -0.22606 -0.25908)
						(xy -0.22733 -0.27051) (xy -0.22733 -0.28067) (xy -0.2286 -0.2921) (xy -0.22733 -0.30353) (xy -0.22733 -0.31369)
						(xy -0.22606 -0.32512) (xy -0.22352 -0.33528) (xy -0.22225 -0.34544) (xy -0.21844 -0.35687) (xy -0.2159 -0.36703)
						(xy -0.21209 -0.37719) (xy -0.20701 -0.38735) (xy -0.2032 -0.39624) (xy -0.19812 -0.4064) (xy -0.17272 -0.44196)
						(xy -0.1651 -0.44958) (xy -0.1651 -0.7366) (xy -0.16256 -0.76835) (xy -0.1524 -0.8001) (xy -0.13716 -0.82804)
						(xy -0.11684 -0.85344) (xy -0.09144 -0.87376) (xy -0.0635 -0.889) (xy -0.03175 -0.89916) (xy 0 -0.9017)
						(xy 0.03175 -0.89916) (xy 0.0635 -0.889) (xy 0.09144 -0.87376) (xy 0.11684 -0.85344) (xy 0.13716 -0.82804)
						(xy 0.1524 -0.8001) (xy 0.16256 -0.76835) (xy 0.1651 -0.7366) (xy 0.1651 -0.44958) (xy 0.17272 -0.44196)
						(xy 0.19812 -0.4064) (xy 0.2032 -0.39624) (xy 0.20701 -0.38735) (xy 0.21209 -0.37719) (xy 0.2159 -0.36703)
						(xy 0.21844 -0.35687) (xy 0.22225 -0.34544) (xy 0.22352 -0.33528) (xy 0.22606 -0.32512) (xy 0.22733 -0.31369)
						(xy 0.22733 -0.30353) (xy 0.2286 -0.2921) (xy 0.22733 -0.28067) (xy 0.22733 -0.27051) (xy 0.22606 -0.25908)
						(xy 0.22352 -0.24892) (xy 0.22225 -0.23876) (xy 0.21844 -0.22733) (xy 0.2159 -0.21717) (xy 0.21209 -0.20701)
						(xy 0.20701 -0.19685) (xy 0.2032 -0.18796) (xy 0.19812 -0.1778) (xy 0.17272 -0.14224) (xy 0.1651 -0.13462)
						(xy 0.1651 0.7366) (xy 0.16256 0.76835) (xy 0.1524 0.8001) (xy 0.13716 0.82804) (xy 0.11684 0.85344)
						(xy 0.09144 0.87376) (xy 0.0635 0.889) (xy 0.03175 0.89916)
					)
					(width 0)
					(fill yes)
				)
			)
		)
		(pad "38" smd custom
			(at -20.550124 -4.106672)
			(size 0.1143 0.1143)
			(layers "F.Cu" "F.Mask" "F.Paste")
			(net "GND")
			(options
				(clearance outline)
				(anchor circle)
			)
			(primitives
				(gr_poly
					(pts
						(xy 0 0.9017) (xy -0.03175 0.89916) (xy -0.0635 0.889) (xy -0.09144 0.87376) (xy -0.11684 0.85344)
						(xy -0.13716 0.82804) (xy -0.1524 0.8001) (xy -0.16256 0.76835) (xy -0.1651 0.7366) (xy -0.1651 0.44958)
						(xy -0.17272 0.44196) (xy -0.19812 0.4064) (xy -0.2032 0.39624) (xy -0.20701 0.38735) (xy -0.21209 0.37719)
						(xy -0.2159 0.36703) (xy -0.21844 0.35687) (xy -0.22225 0.34544) (xy -0.22352 0.33528) (xy -0.22606 0.32512)
						(xy -0.22733 0.31369) (xy -0.22733 0.30353) (xy -0.2286 0.2921) (xy -0.22733 0.28067) (xy -0.22733 0.27051)
						(xy -0.22606 0.25908) (xy -0.22352 0.24892) (xy -0.22225 0.23876) (xy -0.21844 0.22733) (xy -0.2159 0.21717)
						(xy -0.21209 0.20701) (xy -0.20701 0.19685) (xy -0.2032 0.18796) (xy -0.19812 0.1778) (xy -0.17272 0.14224)
						(xy -0.1651 0.13462) (xy -0.1651 -0.7366) (xy -0.16256 -0.76835) (xy -0.1524 -0.8001) (xy -0.13716 -0.82804)
						(xy -0.11684 -0.85344) (xy -0.09144 -0.87376) (xy -0.0635 -0.889) (xy -0.03175 -0.89916) (xy 0 -0.9017)
						(xy 0.03175 -0.89916) (xy 0.0635 -0.889) (xy 0.09144 -0.87376) (xy 0.11684 -0.85344) (xy 0.13716 -0.82804)
						(xy 0.1524 -0.8001) (xy 0.16256 -0.76835) (xy 0.1651 -0.7366) (xy 0.1651 0.13462) (xy 0.17272 0.14224)
						(xy 0.19812 0.1778) (xy 0.2032 0.18796) (xy 0.20701 0.19685) (xy 0.21209 0.20701) (xy 0.2159 0.21717)
						(xy 0.21844 0.22733) (xy 0.22225 0.23876) (xy 0.22352 0.24892) (xy 0.22606 0.25908) (xy 0.22733 0.27051)
						(xy 0.22733 0.28067) (xy 0.2286 0.2921) (xy 0.22733 0.30353) (xy 0.22733 0.31369) (xy 0.22606 0.32512)
						(xy 0.22352 0.33528) (xy 0.22225 0.34544) (xy 0.21844 0.35687) (xy 0.2159 0.36703) (xy 0.21209 0.37719)
						(xy 0.20701 0.38735) (xy 0.2032 0.39624) (xy 0.19812 0.4064) (xy 0.17272 0.44196) (xy 0.1651 0.44958)
						(xy 0.1651 0.7366) (xy 0.16256 0.76835) (xy 0.1524 0.8001) (xy 0.13716 0.82804) (xy 0.11684 0.85344)
						(xy 0.09144 0.87376) (xy 0.0635 0.889) (xy 0.03175 0.89916)
					)
					(width 0)
					(fill yes)
				)
			)
		)
		(pad "39" smd custom
			(at -20.249896 4.106672)
			(size 0.1143 0.1143)
			(layers "F.Cu" "F.Mask" "F.Paste")
			(net "M_B_DQ21")
			(options
				(clearance outline)
				(anchor circle)
			)
			(primitives
				(gr_poly
					(pts
						(xy 0 0.9017) (xy -0.03175 0.89916) (xy -0.0635 0.889) (xy -0.09144 0.87376) (xy -0.11684 0.85344)
						(xy -0.13716 0.82804) (xy -0.1524 0.8001) (xy -0.16256 0.76835) (xy -0.1651 0.7366) (xy -0.1651 0.11938)
						(xy -0.17272 0.11176) (xy -0.19812 0.0762) (xy -0.2032 0.06604) (xy -0.20701 0.05715) (xy -0.21209 0.04699)
						(xy -0.2159 0.03683) (xy -0.21844 0.02667) (xy -0.22225 0.01524) (xy -0.22352 0.00508) (xy -0.22606 -0.00508)
						(xy -0.22733 -0.01651) (xy -0.22733 -0.02667) (xy -0.2286 -0.0381) (xy -0.22733 -0.04953) (xy -0.22733 -0.05969)
						(xy -0.22606 -0.07112) (xy -0.22352 -0.08128) (xy -0.22225 -0.09144) (xy -0.21844 -0.10287) (xy -0.2159 -0.11303)
						(xy -0.21209 -0.12319) (xy -0.20701 -0.13335) (xy -0.2032 -0.14224) (xy -0.19812 -0.1524) (xy -0.17272 -0.18796)
						(xy -0.1651 -0.19558) (xy -0.1651 -0.7366) (xy -0.16256 -0.76835) (xy -0.1524 -0.8001) (xy -0.13716 -0.82804)
						(xy -0.11684 -0.85344) (xy -0.09144 -0.87376) (xy -0.0635 -0.889) (xy -0.03175 -0.89916) (xy 0 -0.9017)
						(xy 0.03175 -0.89916) (xy 0.0635 -0.889) (xy 0.09144 -0.87376) (xy 0.11684 -0.85344) (xy 0.13716 -0.82804)
						(xy 0.1524 -0.8001) (xy 0.16256 -0.76835) (xy 0.1651 -0.7366) (xy 0.1651 -0.19685) (xy 0.17272 -0.18923)
						(xy 0.17907 -0.18034) (xy 0.18669 -0.17145) (xy 0.19177 -0.16256) (xy 0.19812 -0.15367) (xy 0.20828 -0.13335)
						(xy 0.21971 -0.10287) (xy 0.22225 -0.09271) (xy 0.22479 -0.08128) (xy 0.22606 -0.07112) (xy 0.2286 -0.05969)
						(xy 0.2286 -0.01651) (xy 0.22606 -0.00508) (xy 0.22479 0.00508) (xy 0.22225 0.01651) (xy 0.21971 0.02667)
						(xy 0.20828 0.05715) (xy 0.19812 0.07747) (xy 0.19177 0.08636) (xy 0.18669 0.09525) (xy 0.17907 0.10414)
						(xy 0.17272 0.11303) (xy 0.1651 0.12065) (xy 0.1651 0.7366) (xy 0.16256 0.76835) (xy 0.1524 0.8001)
						(xy 0.13716 0.82804) (xy 0.11684 0.85344) (xy 0.09144 0.87376) (xy 0.0635 0.889) (xy 0.03175 0.89916)
					)
					(width 0)
					(fill yes)
				)
			)
		)
		(pad "40" smd custom
			(at -19.949922 -4.106672)
			(size 0.1143 0.1143)
			(layers "F.Cu" "F.Mask" "F.Paste")
			(net "M_B_DQ16")
			(options
				(clearance outline)
				(anchor circle)
			)
			(primitives
				(gr_poly
					(pts
						(xy 0 0.9017) (xy -0.03175 0.89916) (xy -0.0635 0.889) (xy -0.09144 0.87376) (xy -0.11684 0.85344)
						(xy -0.13716 0.82804) (xy -0.1524 0.8001) (xy -0.16256 0.76835) (xy -0.1651 0.7366) (xy -0.1651 0.19685)
						(xy -0.17272 0.18923) (xy -0.17907 0.18034) (xy -0.18669 0.17145) (xy -0.19177 0.16256) (xy -0.19812 0.15367)
						(xy -0.20828 0.13335) (xy -0.21971 0.10287) (xy -0.22225 0.09271) (xy -0.22479 0.08128) (xy -0.22606 0.07112)
						(xy -0.2286 0.05969) (xy -0.2286 0.01651) (xy -0.22606 0.00508) (xy -0.22479 -0.00508) (xy -0.22225 -0.01651)
						(xy -0.21971 -0.02667) (xy -0.20828 -0.05715) (xy -0.19812 -0.07747) (xy -0.19177 -0.08636) (xy -0.18669 -0.09525)
						(xy -0.17907 -0.10414) (xy -0.17272 -0.11303) (xy -0.1651 -0.12065) (xy -0.1651 -0.7366) (xy -0.16256 -0.76835)
						(xy -0.1524 -0.8001) (xy -0.13716 -0.82804) (xy -0.11684 -0.85344) (xy -0.09144 -0.87376) (xy -0.0635 -0.889)
						(xy -0.03175 -0.89916) (xy 0 -0.9017) (xy 0.03175 -0.89916) (xy 0.0635 -0.889) (xy 0.09144 -0.87376)
						(xy 0.11684 -0.85344) (xy 0.13716 -0.82804) (xy 0.1524 -0.8001) (xy 0.16256 -0.76835) (xy 0.1651 -0.7366)
						(xy 0.1651 -0.11938) (xy 0.17272 -0.11176) (xy 0.19812 -0.0762) (xy 0.2032 -0.06604) (xy 0.20701 -0.05715)
						(xy 0.21209 -0.04699) (xy 0.2159 -0.03683) (xy 0.21844 -0.02667) (xy 0.22225 -0.01524) (xy 0.22352 -0.00508)
						(xy 0.22606 0.00508) (xy 0.22733 0.01651) (xy 0.22733 0.02667) (xy 0.2286 0.0381) (xy 0.22733 0.04953)
						(xy 0.22733 0.05969) (xy 0.22606 0.07112) (xy 0.22352 0.08128) (xy 0.22225 0.09144) (xy 0.21844 0.10287)
						(xy 0.2159 0.11303) (xy 0.21209 0.12319) (xy 0.20701 0.13335) (xy 0.2032 0.14224) (xy 0.19812 0.1524)
						(xy 0.17272 0.18796) (xy 0.1651 0.19558) (xy 0.1651 0.7366) (xy 0.16256 0.76835) (xy 0.1524 0.8001)
						(xy 0.13716 0.82804) (xy 0.11684 0.85344) (xy 0.09144 0.87376) (xy 0.0635 0.889) (xy 0.03175 0.89916)
					)
					(width 0)
					(fill yes)
				)
			)
		)
		(pad "41" smd custom
			(at -19.649948 4.106672)
			(size 0.1143 0.1143)
			(layers "F.Cu" "F.Mask" "F.Paste")
			(net "GND")
			(options
				(clearance outline)
				(anchor circle)
			)
			(primitives
				(gr_poly
					(pts
						(xy 0 0.9017) (xy -0.03175 0.89916) (xy -0.0635 0.889) (xy -0.09144 0.87376) (xy -0.11684 0.85344)
						(xy -0.13716 0.82804) (xy -0.1524 0.8001) (xy -0.16256 0.76835) (xy -0.1651 0.7366) (xy -0.1651 -0.13462)
						(xy -0.17272 -0.14224) (xy -0.19812 -0.1778) (xy -0.2032 -0.18796) (xy -0.20701 -0.19685) (xy -0.21209 -0.20701)
						(xy -0.2159 -0.21717) (xy -0.21844 -0.22733) (xy -0.22225 -0.23876) (xy -0.22352 -0.24892) (xy -0.22606 -0.25908)
						(xy -0.22733 -0.27051) (xy -0.22733 -0.28067) (xy -0.2286 -0.2921) (xy -0.22733 -0.30353) (xy -0.22733 -0.31369)
						(xy -0.22606 -0.32512) (xy -0.22352 -0.33528) (xy -0.22225 -0.34544) (xy -0.21844 -0.35687) (xy -0.2159 -0.36703)
						(xy -0.21209 -0.37719) (xy -0.20701 -0.38735) (xy -0.2032 -0.39624) (xy -0.19812 -0.4064) (xy -0.17272 -0.44196)
						(xy -0.1651 -0.44958) (xy -0.1651 -0.7366) (xy -0.16256 -0.76835) (xy -0.1524 -0.8001) (xy -0.13716 -0.82804)
						(xy -0.11684 -0.85344) (xy -0.09144 -0.87376) (xy -0.0635 -0.889) (xy -0.03175 -0.89916) (xy 0 -0.9017)
						(xy 0.03175 -0.89916) (xy 0.0635 -0.889) (xy 0.09144 -0.87376) (xy 0.11684 -0.85344) (xy 0.13716 -0.82804)
						(xy 0.1524 -0.8001) (xy 0.16256 -0.76835) (xy 0.1651 -0.7366) (xy 0.1651 -0.44958) (xy 0.17272 -0.44196)
						(xy 0.19812 -0.4064) (xy 0.2032 -0.39624) (xy 0.20701 -0.38735) (xy 0.21209 -0.37719) (xy 0.2159 -0.36703)
						(xy 0.21844 -0.35687) (xy 0.22225 -0.34544) (xy 0.22352 -0.33528) (xy 0.22606 -0.32512) (xy 0.22733 -0.31369)
						(xy 0.22733 -0.30353) (xy 0.2286 -0.2921) (xy 0.22733 -0.28067) (xy 0.22733 -0.27051) (xy 0.22606 -0.25908)
						(xy 0.22352 -0.24892) (xy 0.22225 -0.23876) (xy 0.21844 -0.22733) (xy 0.2159 -0.21717) (xy 0.21209 -0.20701)
						(xy 0.20701 -0.19685) (xy 0.2032 -0.18796) (xy 0.19812 -0.1778) (xy 0.17272 -0.14224) (xy 0.1651 -0.13462)
						(xy 0.1651 0.7366) (xy 0.16256 0.76835) (xy 0.1524 0.8001) (xy 0.13716 0.82804) (xy 0.11684 0.85344)
						(xy 0.09144 0.87376) (xy 0.0635 0.889) (xy 0.03175 0.89916)
					)
					(width 0)
					(fill yes)
				)
			)
		)
	)
)
